(kicad_pcb
	(version 20260206)
	(generator "pcbnew")
	(generator_version "10.0")
	(general
		(thickness 1.6)
		(legacy_teardrops no)
	)
	(paper "A4")
	(title_block
		(title "03242023_DA0F0TMBIJ0_F0T_Motherboard_J_brd_V01_OCP.brd")
		(comment 1 "Grand Teton / footprints 4676-4683 of 6105")
	)
	(layers
		(0 "F.Cu" signal "TOP")
		(4 "In1.Cu" signal "GND")
		(6 "In2.Cu" signal "IN1")
		(8 "In3.Cu" signal "GND1")
		(10 "In4.Cu" signal "IN2")
		(12 "In5.Cu" signal "GND2")
		(14 "In6.Cu" signal "IN3")
		(16 "In7.Cu" signal "GND3")
		(18 "In8.Cu" signal "VCC")
		(20 "In9.Cu" signal "VCC1")
		(22 "In10.Cu" signal "GND4")
		(24 "In11.Cu" signal "IN4")
		(26 "In12.Cu" signal "GND5")
		(28 "In13.Cu" signal "IN5")
		(30 "In14.Cu" signal "GND6")
		(32 "In15.Cu" signal "IN6")
		(34 "In16.Cu" signal "GND7")
		(2 "B.Cu" signal "BOTTOM")
		(9 "F.Adhes" user "F.Adhesive")
		(11 "B.Adhes" user "B.Adhesive")
		(13 "F.Paste" user "Package Geometry/Pastemask Top")
		(15 "B.Paste" user "Package Geometry/Pastemask Bottom")
		(5 "F.SilkS" user "Ref Des/Silkscreen Top")
		(7 "B.SilkS" user "Ref Des/Silkscreen Bottom")
		(1 "F.Mask" user "Board Geometry/Soldermask Top")
		(3 "B.Mask" user "Board Geometry/Soldermask Bottom")
		(17 "Dwgs.User" user "User.Drawings")
		(19 "Cmts.User" user "User.Comments")
		(21 "Eco1.User" user "User.Eco1")
		(23 "Eco2.User" user "User.Eco2")
		(25 "Edge.Cuts" user "Board Geometry/Outline")
		(27 "Margin" user)
		(31 "F.CrtYd" user "Package Geometry/Place Bound Top")
		(29 "B.CrtYd" user "Package Geometry/Place Bound Bottom")
		(35 "F.Fab" user "Ref Des/Assembly Top")
		(33 "B.Fab" user "Ref Des/Assembly Bottom")
	)
	(footprint ""
		(layer "B.Cu")
		(at 444.485014 -319.263776 180)
		(property "Reference" "C38"
			(at 0 0 0)
			(layer "B.SilkS")
			(hide yes)
			(effects
				(font
					(size 1.27 1.27)
				)
				(justify mirror)
			)
		)
		(property "Value" ""
			(at 0 0 0)
			(layer "B.Fab")
			(effects
				(font
					(size 1.27 1.27)
				)
				(justify mirror)
			)
		)
		(duplicate_pad_numbers_are_jumpers no)
		(fp_line
			(start 0.7874 0.4064)
			(end 0.7874 -0.4064)
			(stroke
				(width 0.1524)
				(type default)
			)
			(layer "B.SilkS")
		)
		(fp_line
			(start 0.7874 -0.4064)
			(end -0.7874 -0.4064)
			(stroke
				(width 0.1524)
				(type default)
			)
			(layer "B.SilkS")
		)
		(fp_line
			(start -0.7874 0.4064)
			(end 0.7874 0.4064)
			(stroke
				(width 0.1524)
				(type default)
			)
			(layer "B.SilkS")
		)
		(fp_line
			(start -0.7874 -0.4064)
			(end -0.7874 0.4064)
			(stroke
				(width 0.1524)
				(type default)
			)
			(layer "B.SilkS")
		)
		(fp_line
			(start 0.67945 0.3048)
			(end 0.67945 -0.305054)
			(stroke
				(width 0.1)
				(type default)
			)
			(layer "B.Fab")
		)
		(fp_line
			(start 0.67945 -0.305054)
			(end 0.12065 -0.305054)
			(stroke
				(width 0.1)
				(type default)
			)
			(layer "B.Fab")
		)
		(fp_line
			(start 0.12065 0.3048)
			(end 0.67945 0.3048)
			(stroke
				(width 0.1)
				(type default)
			)
			(layer "B.Fab")
		)
		(fp_line
			(start 0.12065 0.2794)
			(end 0.12065 0.3048)
			(stroke
				(width 0.1)
				(type default)
			)
			(layer "B.Fab")
		)
		(fp_line
			(start 0.12065 -0.2794)
			(end -0.12065 -0.2794)
			(stroke
				(width 0.1)
				(type default)
			)
			(layer "B.Fab")
		)
		(fp_line
			(start 0.12065 -0.305054)
			(end 0.12065 -0.2794)
			(stroke
				(width 0.1)
				(type default)
			)
			(layer "B.Fab")
		)
		(fp_line
			(start -0.120396 0.3048)
			(end -0.120396 0.2794)
			(stroke
				(width 0.1)
				(type default)
			)
			(layer "B.Fab")
		)
		(fp_line
			(start -0.120396 0.2794)
			(end 0.12065 0.2794)
			(stroke
				(width 0.1)
				(type default)
			)
			(layer "B.Fab")
		)
		(fp_line
			(start -0.12065 -0.2794)
			(end -0.12065 -0.3048)
			(stroke
				(width 0.1)
				(type default)
			)
			(layer "B.Fab")
		)
		(fp_line
			(start -0.12065 -0.3048)
			(end -0.67945 -0.3048)
			(stroke
				(width 0.1)
				(type default)
			)
			(layer "B.Fab")
		)
		(fp_line
			(start -0.67945 0.3048)
			(end -0.120396 0.3048)
			(stroke
				(width 0.1)
				(type default)
			)
			(layer "B.Fab")
		)
		(fp_line
			(start -0.67945 -0.3048)
			(end -0.67945 0.3048)
			(stroke
				(width 0.1)
				(type default)
			)
			(layer "B.Fab")
		)
		(pad "1" smd circle
			(at 0.40005 0)
			(size 0 0)
			(layers "B.Cu" "B.Mask" "B.Paste")
			(net "P3V3_AUX")
		)
		(pad "2" smd circle
			(at -0.40005 0)
			(size 0 0)
			(layers "B.Cu" "B.Mask" "B.Paste")
			(net "GND")
		)
	)
	(footprint ""
		(layer "B.Cu")
		(at 83.62315 -52.082446 180)
		(property "Reference" "R3833"
			(at 0 0 0)
			(layer "B.SilkS")
			(hide yes)
			(effects
				(font
					(size 1.27 1.27)
				)
				(justify mirror)
			)
		)
		(property "Value" ""
			(at 0 0 0)
			(layer "B.Fab")
			(effects
				(font
					(size 1.27 1.27)
				)
				(justify mirror)
			)
		)
		(duplicate_pad_numbers_are_jumpers no)
		(fp_line
			(start 0.7874 0.4064)
			(end 0.7874 -0.4064)
			(stroke
				(width 0.1524)
				(type default)
			)
			(layer "B.SilkS")
		)
		(fp_line
			(start 0.7874 -0.4064)
			(end -0.7874 -0.4064)
			(stroke
				(width 0.1524)
				(type default)
			)
			(layer "B.SilkS")
		)
		(fp_line
			(start -0.7874 0.4064)
			(end 0.7874 0.4064)
			(stroke
				(width 0.1524)
				(type default)
			)
			(layer "B.SilkS")
		)
		(fp_line
			(start -0.7874 -0.4064)
			(end -0.7874 0.4064)
			(stroke
				(width 0.1524)
				(type default)
			)
			(layer "B.SilkS")
		)
		(fp_line
			(start 0.67945 0.3048)
			(end 0.67945 -0.305054)
			(stroke
				(width 0.1)
				(type default)
			)
			(layer "B.Fab")
		)
		(fp_line
			(start 0.67945 -0.305054)
			(end 0.12065 -0.305054)
			(stroke
				(width 0.1)
				(type default)
			)
			(layer "B.Fab")
		)
		(fp_line
			(start 0.12065 0.3048)
			(end 0.67945 0.3048)
			(stroke
				(width 0.1)
				(type default)
			)
			(layer "B.Fab")
		)
		(fp_line
			(start 0.12065 0.2794)
			(end 0.12065 0.3048)
			(stroke
				(width 0.1)
				(type default)
			)
			(layer "B.Fab")
		)
		(fp_line
			(start 0.12065 -0.2794)
			(end -0.12065 -0.2794)
			(stroke
				(width 0.1)
				(type default)
			)
			(layer "B.Fab")
		)
		(fp_line
			(start 0.12065 -0.305054)
			(end 0.12065 -0.2794)
			(stroke
				(width 0.1)
				(type default)
			)
			(layer "B.Fab")
		)
		(fp_line
			(start -0.120396 0.3048)
			(end -0.120396 0.2794)
			(stroke
				(width 0.1)
				(type default)
			)
			(layer "B.Fab")
		)
		(fp_line
			(start -0.120396 0.2794)
			(end 0.12065 0.2794)
			(stroke
				(width 0.1)
				(type default)
			)
			(layer "B.Fab")
		)
		(fp_line
			(start -0.12065 -0.2794)
			(end -0.12065 -0.3048)
			(stroke
				(width 0.1)
				(type default)
			)
			(layer "B.Fab")
		)
		(fp_line
			(start -0.12065 -0.3048)
			(end -0.67945 -0.3048)
			(stroke
				(width 0.1)
				(type default)
			)
			(layer "B.Fab")
		)
		(fp_line
			(start -0.67945 0.3048)
			(end -0.120396 0.3048)
			(stroke
				(width 0.1)
				(type default)
			)
			(layer "B.Fab")
		)
		(fp_line
			(start -0.67945 -0.3048)
			(end -0.67945 0.3048)
			(stroke
				(width 0.1)
				(type default)
			)
			(layer "B.Fab")
		)
		(pad "1" smd circle
			(at 0.40005 0)
			(size 0 0)
			(layers "B.Cu" "B.Mask" "B.Paste")
			(net "P3V3_AUX")
		)
		(pad "2" smd circle
			(at -0.40005 0)
			(size 0 0)
			(layers "B.Cu" "B.Mask" "B.Paste")
			(net "P3V3_OCP_FAULT_2")
		)
	)
	(footprint ""
		(layer "B.Cu")
		(at 346.497148 -31.527242 180)
		(property "Reference" "R2348"
			(at 0 0 0)
			(layer "B.SilkS")
			(hide yes)
			(effects
				(font
					(size 1.27 1.27)
				)
				(justify mirror)
			)
		)
		(property "Value" ""
			(at 0 0 0)
			(layer "B.Fab")
			(effects
				(font
					(size 1.27 1.27)
				)
				(justify mirror)
			)
		)
		(duplicate_pad_numbers_are_jumpers no)
		(fp_line
			(start 0.7874 0.4064)
			(end 0.7874 -0.4064)
			(stroke
				(width 0.1524)
				(type default)
			)
			(layer "B.SilkS")
		)
		(fp_line
			(start 0.7874 -0.4064)
			(end -0.7874 -0.4064)
			(stroke
				(width 0.1524)
				(type default)
			)
			(layer "B.SilkS")
		)
		(fp_line
			(start -0.7874 0.4064)
			(end 0.7874 0.4064)
			(stroke
				(width 0.1524)
				(type default)
			)
			(layer "B.SilkS")
		)
		(fp_line
			(start -0.7874 -0.4064)
			(end -0.7874 0.4064)
			(stroke
				(width 0.1524)
				(type default)
			)
			(layer "B.SilkS")
		)
		(fp_line
			(start 0.67945 0.3048)
			(end 0.67945 -0.305054)
			(stroke
				(width 0.1)
				(type default)
			)
			(layer "B.Fab")
		)
		(fp_line
			(start 0.67945 -0.305054)
			(end 0.12065 -0.305054)
			(stroke
				(width 0.1)
				(type default)
			)
			(layer "B.Fab")
		)
		(fp_line
			(start 0.12065 0.3048)
			(end 0.67945 0.3048)
			(stroke
				(width 0.1)
				(type default)
			)
			(layer "B.Fab")
		)
		(fp_line
			(start 0.12065 0.2794)
			(end 0.12065 0.3048)
			(stroke
				(width 0.1)
				(type default)
			)
			(layer "B.Fab")
		)
		(fp_line
			(start 0.12065 -0.2794)
			(end -0.12065 -0.2794)
			(stroke
				(width 0.1)
				(type default)
			)
			(layer "B.Fab")
		)
		(fp_line
			(start 0.12065 -0.305054)
			(end 0.12065 -0.2794)
			(stroke
				(width 0.1)
				(type default)
			)
			(layer "B.Fab")
		)
		(fp_line
			(start -0.120396 0.3048)
			(end -0.120396 0.2794)
			(stroke
				(width 0.1)
				(type default)
			)
			(layer "B.Fab")
		)
		(fp_line
			(start -0.120396 0.2794)
			(end 0.12065 0.2794)
			(stroke
				(width 0.1)
				(type default)
			)
			(layer "B.Fab")
		)
		(fp_line
			(start -0.12065 -0.2794)
			(end -0.12065 -0.3048)
			(stroke
				(width 0.1)
				(type default)
			)
			(layer "B.Fab")
		)
		(fp_line
			(start -0.12065 -0.3048)
			(end -0.67945 -0.3048)
			(stroke
				(width 0.1)
				(type default)
			)
			(layer "B.Fab")
		)
		(fp_line
			(start -0.67945 0.3048)
			(end -0.120396 0.3048)
			(stroke
				(width 0.1)
				(type default)
			)
			(layer "B.Fab")
		)
		(fp_line
			(start -0.67945 -0.3048)
			(end -0.67945 0.3048)
			(stroke
				(width 0.1)
				(type default)
			)
			(layer "B.Fab")
		)
		(pad "1" smd circle
			(at 0.40005 0)
			(size 0 0)
			(layers "B.Cu" "B.Mask" "B.Paste")
			(net "FM_DEBUG_PORT_PRSNT_N")
		)
		(pad "2" smd circle
			(at -0.40005 0)
			(size 0 0)
			(layers "B.Cu" "B.Mask" "B.Paste")
			(net "FM_DEBUG_PORT_PRSNT_R_N")
		)
	)
	(footprint ""
		(layer "B.Cu")
		(at 192.724532 -423.657014 -90)
		(property "Reference" "R4703"
			(at 0 0 90)
			(layer "B.SilkS")
			(hide yes)
			(effects
				(font
					(size 1.27 1.27)
				)
				(justify mirror)
			)
		)
		(property "Value" ""
			(at 0 0 90)
			(layer "B.Fab")
			(effects
				(font
					(size 1.27 1.27)
				)
				(justify mirror)
			)
		)
		(duplicate_pad_numbers_are_jumpers no)
		(fp_line
			(start -0.7874 0.4064)
			(end 0.7874 0.4064)
			(stroke
				(width 0.1524)
				(type default)
			)
			(layer "B.SilkS")
		)
		(fp_line
			(start 0.7874 0.4064)
			(end 0.7874 -0.4064)
			(stroke
				(width 0.1524)
				(type default)
			)
			(layer "B.SilkS")
		)
		(fp_line
			(start -0.7874 -0.4064)
			(end -0.7874 0.4064)
			(stroke
				(width 0.1524)
				(type default)
			)
			(layer "B.SilkS")
		)
		(fp_line
			(start 0.7874 -0.4064)
			(end -0.7874 -0.4064)
			(stroke
				(width 0.1524)
				(type default)
			)
			(layer "B.SilkS")
		)
		(fp_line
			(start -0.67945 0.3048)
			(end -0.120396 0.3048)
			(stroke
				(width 0.1)
				(type default)
			)
			(layer "B.Fab")
		)
		(fp_line
			(start -0.120396 0.3048)
			(end -0.120396 0.2794)
			(stroke
				(width 0.1)
				(type default)
			)
			(layer "B.Fab")
		)
		(fp_line
			(start 0.12065 0.3048)
			(end 0.67945 0.3048)
			(stroke
				(width 0.1)
				(type default)
			)
			(layer "B.Fab")
		)
		(fp_line
			(start 0.67945 0.3048)
			(end 0.67945 -0.305054)
			(stroke
				(width 0.1)
				(type default)
			)
			(layer "B.Fab")
		)
		(fp_line
			(start -0.120396 0.2794)
			(end 0.12065 0.2794)
			(stroke
				(width 0.1)
				(type default)
			)
			(layer "B.Fab")
		)
		(fp_line
			(start 0.12065 0.2794)
			(end 0.12065 0.3048)
			(stroke
				(width 0.1)
				(type default)
			)
			(layer "B.Fab")
		)
		(fp_line
			(start -0.12065 -0.2794)
			(end -0.12065 -0.3048)
			(stroke
				(width 0.1)
				(type default)
			)
			(layer "B.Fab")
		)
		(fp_line
			(start 0.12065 -0.2794)
			(end -0.12065 -0.2794)
			(stroke
				(width 0.1)
				(type default)
			)
			(layer "B.Fab")
		)
		(fp_line
			(start -0.67945 -0.3048)
			(end -0.67945 0.3048)
			(stroke
				(width 0.1)
				(type default)
			)
			(layer "B.Fab")
		)
		(fp_line
			(start -0.12065 -0.3048)
			(end -0.67945 -0.3048)
			(stroke
				(width 0.1)
				(type default)
			)
			(layer "B.Fab")
		)
		(fp_line
			(start 0.12065 -0.305054)
			(end 0.12065 -0.2794)
			(stroke
				(width 0.1)
				(type default)
			)
			(layer "B.Fab")
		)
		(fp_line
			(start 0.67945 -0.305054)
			(end 0.12065 -0.305054)
			(stroke
				(width 0.1)
				(type default)
			)
			(layer "B.Fab")
		)
		(pad "1" smd circle
			(at 0.40005 0 90)
			(size 0 0)
			(layers "B.Cu" "B.Mask" "B.Paste")
			(net "LED_P12V_PSU_R1")
		)
		(pad "2" smd circle
			(at -0.40005 0 90)
			(size 0 0)
			(layers "B.Cu" "B.Mask" "B.Paste")
			(net "LED_P12V_PSU_R2")
		)
	)
	(footprint ""
		(layer "B.Cu")
		(at 386.861812 -342.936576 90)
		(property "Reference" "PC240_P0_8"
			(at 0 0 90)
			(layer "B.SilkS")
			(hide yes)
			(effects
				(font
					(size 1.27 1.27)
				)
				(justify mirror)
			)
		)
		(property "Value" ""
			(at 0 0 90)
			(layer "B.Fab")
			(effects
				(font
					(size 1.27 1.27)
				)
				(justify mirror)
			)
		)
		(duplicate_pad_numbers_are_jumpers no)
		(fp_line
			(start 1.524 -0.762)
			(end -1.524 -0.762)
			(stroke
				(width 0.1524)
				(type default)
			)
			(layer "B.SilkS")
		)
		(fp_line
			(start -1.524 -0.762)
			(end -1.524 0.762)
			(stroke
				(width 0.1524)
				(type default)
			)
			(layer "B.SilkS")
		)
		(fp_line
			(start 1.524 0.762)
			(end 1.524 -0.762)
			(stroke
				(width 0.1524)
				(type default)
			)
			(layer "B.SilkS")
		)
		(fp_line
			(start -1.524 0.762)
			(end 1.524 0.762)
			(stroke
				(width 0.1524)
				(type default)
			)
			(layer "B.SilkS")
		)
		(fp_line
			(start 1.1049 -0.724916)
			(end 1.1049 0.724916)
			(stroke
				(width 0.1)
				(type default)
			)
			(layer "B.Fab")
		)
		(fp_line
			(start -1.1049 -0.724916)
			(end 1.1049 -0.724916)
			(stroke
				(width 0.1)
				(type default)
			)
			(layer "B.Fab")
		)
		(fp_line
			(start 1.1049 0.724916)
			(end -1.1049 0.724916)
			(stroke
				(width 0.1)
				(type default)
			)
			(layer "B.Fab")
		)
		(fp_line
			(start -1.1049 0.724916)
			(end -1.1049 -0.724916)
			(stroke
				(width 0.1)
				(type default)
			)
			(layer "B.Fab")
		)
		(pad "1" smd rect
			(at 0.889 0 90)
			(size 1.016 1.27)
			(layers "B.Cu" "B.Mask" "B.Paste")
			(net "SW_P12V_PVCCIN_CPU0_FLT")
		)
		(pad "2" smd rect
			(at -0.889 0 90)
			(size 1.016 1.27)
			(layers "B.Cu" "B.Mask" "B.Paste")
			(net "GND")
		)
	)
	(footprint ""
		(layer "B.Cu")
		(at 313.014614 -258.379976 -90)
		(property "Reference" "C526"
			(at 0 0 90)
			(layer "B.SilkS")
			(hide yes)
			(effects
				(font
					(size 1.27 1.27)
				)
				(justify mirror)
			)
		)
		(property "Value" ""
			(at 0 0 90)
			(layer "B.Fab")
			(effects
				(font
					(size 1.27 1.27)
				)
				(justify mirror)
			)
		)
		(duplicate_pad_numbers_are_jumpers no)
		(fp_line
			(start -1.524 0.762)
			(end 1.524 0.762)
			(stroke
				(width 0.1524)
				(type default)
			)
			(layer "B.SilkS")
		)
		(fp_line
			(start 1.524 0.762)
			(end 1.524 -0.762)
			(stroke
				(width 0.1524)
				(type default)
			)
			(layer "B.SilkS")
		)
		(fp_line
			(start -1.524 -0.762)
			(end -1.524 0.762)
			(stroke
				(width 0.1524)
				(type default)
			)
			(layer "B.SilkS")
		)
		(fp_line
			(start 1.524 -0.762)
			(end -1.524 -0.762)
			(stroke
				(width 0.1524)
				(type default)
			)
			(layer "B.SilkS")
		)
		(fp_line
			(start -1.1049 0.724916)
			(end -1.1049 -0.724916)
			(stroke
				(width 0.1)
				(type default)
			)
			(layer "B.Fab")
		)
		(fp_line
			(start 1.1049 0.724916)
			(end -1.1049 0.724916)
			(stroke
				(width 0.1)
				(type default)
			)
			(layer "B.Fab")
		)
		(fp_line
			(start -1.1049 -0.724916)
			(end 1.1049 -0.724916)
			(stroke
				(width 0.1)
				(type default)
			)
			(layer "B.Fab")
		)
		(fp_line
			(start 1.1049 -0.724916)
			(end 1.1049 0.724916)
			(stroke
				(width 0.1)
				(type default)
			)
			(layer "B.Fab")
		)
		(pad "1" smd rect
			(at 0.889 0 270)
			(size 1.016 1.27)
			(layers "B.Cu" "B.Mask" "B.Paste")
			(net "PVCCFA_EHV_FIVRA_CPU0")
		)
		(pad "2" smd rect
			(at -0.889 0 270)
			(size 1.016 1.27)
			(layers "B.Cu" "B.Mask" "B.Paste")
			(net "GND")
		)
	)
	(footprint ""
		(layer "B.Cu")
		(at 105.679494 -252.17628 -90)
		(property "Reference" "C330"
			(at 0 0 90)
			(layer "B.SilkS")
			(hide yes)
			(effects
				(font
					(size 1.27 1.27)
				)
				(justify mirror)
			)
		)
		(property "Value" ""
			(at 0 0 90)
			(layer "B.Fab")
			(effects
				(font
					(size 1.27 1.27)
				)
				(justify mirror)
			)
		)
		(duplicate_pad_numbers_are_jumpers no)
		(fp_line
			(start -1.524 0.762)
			(end 1.524 0.762)
			(stroke
				(width 0.1524)
				(type default)
			)
			(layer "B.SilkS")
		)
		(fp_line
			(start 1.524 0.762)
			(end 1.524 -0.762)
			(stroke
				(width 0.1524)
				(type default)
			)
			(layer "B.SilkS")
		)
		(fp_line
			(start -1.524 -0.762)
			(end -1.524 0.762)
			(stroke
				(width 0.1524)
				(type default)
			)
			(layer "B.SilkS")
		)
		(fp_line
			(start 1.524 -0.762)
			(end -1.524 -0.762)
			(stroke
				(width 0.1524)
				(type default)
			)
			(layer "B.SilkS")
		)
		(fp_line
			(start -1.1049 0.724916)
			(end -1.1049 -0.724916)
			(stroke
				(width 0.1)
				(type default)
			)
			(layer "B.Fab")
		)
		(fp_line
			(start 1.1049 0.724916)
			(end -1.1049 0.724916)
			(stroke
				(width 0.1)
				(type default)
			)
			(layer "B.Fab")
		)
		(fp_line
			(start -1.1049 -0.724916)
			(end 1.1049 -0.724916)
			(stroke
				(width 0.1)
				(type default)
			)
			(layer "B.Fab")
		)
		(fp_line
			(start 1.1049 -0.724916)
			(end 1.1049 0.724916)
			(stroke
				(width 0.1)
				(type default)
			)
			(layer "B.Fab")
		)
		(pad "1" smd rect
			(at 0.889 0 270)
			(size 1.016 1.27)
			(layers "B.Cu" "B.Mask" "B.Paste")
			(net "PVCCIN_CPU1")
		)
		(pad "2" smd rect
			(at -0.889 0 270)
			(size 1.016 1.27)
			(layers "B.Cu" "B.Mask" "B.Paste")
			(net "GND")
		)
	)
	(footprint ""
		(layer "B.Cu")
		(at 105.679494 -259.53212 90)
		(property "Reference" "C461"
			(at 0 0 90)
			(layer "B.SilkS")
			(hide yes)
			(effects
				(font
					(size 1.27 1.27)
				)
				(justify mirror)
			)
		)
		(property "Value" ""
			(at 0 0 90)
			(layer "B.Fab")
			(effects
				(font
					(size 1.27 1.27)
				)
				(justify mirror)
			)
		)
		(duplicate_pad_numbers_are_jumpers no)
		(fp_line
			(start 1.524 -0.762)
			(end -1.524 -0.762)
			(stroke
				(width 0.1524)
				(type default)
			)
			(layer "B.SilkS")
		)
		(fp_line
			(start -1.524 -0.762)
			(end -1.524 0.762)
			(stroke
				(width 0.1524)
				(type default)
			)
			(layer "B.SilkS")
		)
		(fp_line
			(start 1.524 0.762)
			(end 1.524 -0.762)
			(stroke
				(width 0.1524)
				(type default)
			)
			(layer "B.SilkS")
		)
		(fp_line
			(start -1.524 0.762)
			(end 1.524 0.762)
			(stroke
				(width 0.1524)
				(type default)
			)
			(layer "B.SilkS")
		)
		(fp_line
			(start 1.1049 -0.724916)
			(end 1.1049 0.724916)
			(stroke
				(width 0.1)
				(type default)
			)
			(layer "B.Fab")
		)
		(fp_line
			(start -1.1049 -0.724916)
			(end 1.1049 -0.724916)
			(stroke
				(width 0.1)
				(type default)
			)
			(layer "B.Fab")
		)
		(fp_line
			(start 1.1049 0.724916)
			(end -1.1049 0.724916)
			(stroke
				(width 0.1)
				(type default)
			)
			(layer "B.Fab")
		)
		(fp_line
			(start -1.1049 0.724916)
			(end -1.1049 -0.724916)
			(stroke
				(width 0.1)
				(type default)
			)
			(layer "B.Fab")
		)
		(pad "1" smd rect
			(at 0.889 0 90)
			(size 1.016 1.27)
			(layers "B.Cu" "B.Mask" "B.Paste")
			(net "PVCCFA_EHV_FIVRA_CPU1")
		)
		(pad "2" smd rect
			(at -0.889 0 90)
			(size 1.016 1.27)
			(layers "B.Cu" "B.Mask" "B.Paste")
			(net "GND")
		)
	)
)
